(kicad_pcb
	(version 20260206)
	(generator "pcbnew")
	(generator_version "10.0")
	(general
		(thickness 1.6)
		(legacy_teardrops no)
	)
	(paper "A4")
	(title_block
		(title "01162023_DA0F0TEBIF0_F0T_Expander_BD_F_brd_V02_OCP.brd")
		(comment 1 "Grand Teton / footprints 1716-1722 of 9728")
	)
	(layers
		(0 "F.Cu" signal "TOP")
		(4 "In1.Cu" signal "GND")
		(6 "In2.Cu" signal "VCC")
		(8 "In3.Cu" signal "VCC1")
		(10 "In4.Cu" signal "GND1")
		(12 "In5.Cu" signal "IN1")
		(14 "In6.Cu" signal "GND2")
		(16 "In7.Cu" signal "IN2")
		(18 "In8.Cu" signal "GND3")
		(20 "In9.Cu" signal "IN3")
		(22 "In10.Cu" signal "GND4")
		(24 "In11.Cu" signal "IN4")
		(26 "In12.Cu" signal "GND5")
		(28 "In13.Cu" signal "IN5")
		(30 "In14.Cu" signal "GND6")
		(32 "In15.Cu" signal "IN6")
		(34 "In16.Cu" signal "GND7")
		(2 "B.Cu" signal "BOTTOM")
		(9 "F.Adhes" user "F.Adhesive")
		(11 "B.Adhes" user "B.Adhesive")
		(13 "F.Paste" user "Package Geometry/Pastemask Top")
		(15 "B.Paste" user "Package Geometry/Pastemask Bottom")
		(5 "F.SilkS" user "Ref Des/Silkscreen Top")
		(7 "B.SilkS" user "Ref Des/Silkscreen Bottom")
		(1 "F.Mask" user "Board Geometry/Soldermask Top")
		(3 "B.Mask" user "Board Geometry/Soldermask Bottom")
		(17 "Dwgs.User" user "User.Drawings")
		(19 "Cmts.User" user "User.Comments")
		(21 "Eco1.User" user "User.Eco1")
		(23 "Eco2.User" user "User.Eco2")
		(25 "Edge.Cuts" user "Board Geometry/Outline")
		(27 "Margin" user)
		(31 "F.CrtYd" user "Package Geometry/Place Bound Top")
		(29 "B.CrtYd" user "Package Geometry/Place Bound Bottom")
		(35 "F.Fab" user "Ref Des/Assembly Top")
		(33 "B.Fab" user "Ref Des/Assembly Bottom")
	)
	(footprint ""
		(layer "F.Cu")
		(at 363.842808 -162.003994 -90)
		(property "Reference" "C981"
			(at 0 0 270)
			(layer "F.SilkS")
			(hide yes)
			(effects
				(font
					(size 1.27 1.27)
				)
			)
		)
		(property "Value" ""
			(at 0 0 270)
			(layer "F.Fab")
			(effects
				(font
					(size 1.27 1.27)
				)
			)
		)
		(duplicate_pad_numbers_are_jumpers no)
		(fp_line
			(start -0.7874 0.4064)
			(end -0.7874 -0.4064)
			(stroke
				(width 0.1524)
				(type default)
			)
			(layer "F.SilkS")
		)
		(fp_line
			(start 0.7874 0.4064)
			(end -0.7874 0.4064)
			(stroke
				(width 0.1524)
				(type default)
			)
			(layer "F.SilkS")
		)
		(fp_line
			(start -0.7874 -0.4064)
			(end 0.7874 -0.4064)
			(stroke
				(width 0.1524)
				(type default)
			)
			(layer "F.SilkS")
		)
		(fp_line
			(start 0.7874 -0.4064)
			(end 0.7874 0.4064)
			(stroke
				(width 0.1524)
				(type default)
			)
			(layer "F.SilkS")
		)
		(fp_line
			(start -0.67945 0.3048)
			(end -0.67945 -0.305054)
			(stroke
				(width 0.1)
				(type default)
			)
			(layer "F.Fab")
		)
		(fp_line
			(start -0.12065 0.3048)
			(end -0.67945 0.3048)
			(stroke
				(width 0.1)
				(type default)
			)
			(layer "F.Fab")
		)
		(fp_line
			(start 0.120396 0.3048)
			(end 0.120396 0.2794)
			(stroke
				(width 0.1)
				(type default)
			)
			(layer "F.Fab")
		)
		(fp_line
			(start 0.67945 0.3048)
			(end 0.120396 0.3048)
			(stroke
				(width 0.1)
				(type default)
			)
			(layer "F.Fab")
		)
		(fp_line
			(start -0.12065 0.2794)
			(end -0.12065 0.3048)
			(stroke
				(width 0.1)
				(type default)
			)
			(layer "F.Fab")
		)
		(fp_line
			(start 0.120396 0.2794)
			(end -0.12065 0.2794)
			(stroke
				(width 0.1)
				(type default)
			)
			(layer "F.Fab")
		)
		(fp_line
			(start -0.12065 -0.2794)
			(end 0.12065 -0.2794)
			(stroke
				(width 0.1)
				(type default)
			)
			(layer "F.Fab")
		)
		(fp_line
			(start 0.12065 -0.2794)
			(end 0.12065 -0.3048)
			(stroke
				(width 0.1)
				(type default)
			)
			(layer "F.Fab")
		)
		(fp_line
			(start 0.12065 -0.3048)
			(end 0.67945 -0.3048)
			(stroke
				(width 0.1)
				(type default)
			)
			(layer "F.Fab")
		)
		(fp_line
			(start 0.67945 -0.3048)
			(end 0.67945 0.3048)
			(stroke
				(width 0.1)
				(type default)
			)
			(layer "F.Fab")
		)
		(fp_line
			(start -0.67945 -0.305054)
			(end -0.12065 -0.305054)
			(stroke
				(width 0.1)
				(type default)
			)
			(layer "F.Fab")
		)
		(fp_line
			(start -0.12065 -0.305054)
			(end -0.12065 -0.2794)
			(stroke
				(width 0.1)
				(type default)
			)
			(layer "F.Fab")
		)
		(pad "1" smd circle
			(at -0.40005 0 270)
			(size 0 0)
			(layers "F.Cu" "F.Mask" "F.Paste")
			(net "GND")
		)
		(pad "2" smd circle
			(at 0.40005 0 270)
			(size 0 0)
			(layers "F.Cu" "F.Mask" "F.Paste")
			(net "P12V_NIC6_CO_EN")
		)
	)
	(footprint ""
		(layer "F.Cu")
		(at 36.638484 -112.809782)
		(property "Reference" "C50"
			(at 0 0 0)
			(layer "F.SilkS")
			(hide yes)
			(effects
				(font
					(size 1.27 1.27)
				)
			)
		)
		(property "Value" ""
			(at 0 0 0)
			(layer "F.Fab")
			(effects
				(font
					(size 1.27 1.27)
				)
			)
		)
		(duplicate_pad_numbers_are_jumpers no)
		(fp_line
			(start -0.299974 -0.150114)
			(end 0.299974 -0.150114)
			(stroke
				(width 0.1)
				(type default)
			)
			(layer "F.Fab")
		)
		(fp_line
			(start -0.299974 0.150114)
			(end -0.299974 -0.150114)
			(stroke
				(width 0.1)
				(type default)
			)
			(layer "F.Fab")
		)
		(fp_line
			(start 0.299974 -0.150114)
			(end 0.299974 0.150114)
			(stroke
				(width 0.1)
				(type default)
			)
			(layer "F.Fab")
		)
		(fp_line
			(start 0.299974 0.150114)
			(end -0.299974 0.150114)
			(stroke
				(width 0.1)
				(type default)
			)
			(layer "F.Fab")
		)
		(pad "1" smd rect
			(at -0.2667 0)
			(size 0.3048 0.381)
			(layers "F.Cu" "F.Mask" "F.Paste")
			(net "P5E_PEX0_STN1_TX_DP<23>")
		)
		(pad "2" smd rect
			(at 0.2667 0)
			(size 0.3048 0.381)
			(layers "F.Cu" "F.Mask" "F.Paste")
			(net "P5E_PEX0_STN1_TX_C_DP<23>")
		)
	)
	(footprint ""
		(layer "F.Cu")
		(at 257.558286 -250.070874 -90)
		(property "Reference" "R1343"
			(at 0 0 270)
			(layer "F.SilkS")
			(hide yes)
			(effects
				(font
					(size 1.27 1.27)
				)
			)
		)
		(property "Value" ""
			(at 0 0 270)
			(layer "F.Fab")
			(effects
				(font
					(size 1.27 1.27)
				)
			)
		)
		(duplicate_pad_numbers_are_jumpers no)
		(fp_line
			(start -0.7874 0.4064)
			(end -0.7874 -0.4064)
			(stroke
				(width 0.1524)
				(type default)
			)
			(layer "F.SilkS")
		)
		(fp_line
			(start 0.7874 0.4064)
			(end -0.7874 0.4064)
			(stroke
				(width 0.1524)
				(type default)
			)
			(layer "F.SilkS")
		)
		(fp_line
			(start -0.7874 -0.4064)
			(end 0.7874 -0.4064)
			(stroke
				(width 0.1524)
				(type default)
			)
			(layer "F.SilkS")
		)
		(fp_line
			(start 0.7874 -0.4064)
			(end 0.7874 0.4064)
			(stroke
				(width 0.1524)
				(type default)
			)
			(layer "F.SilkS")
		)
		(fp_line
			(start -0.67945 0.3048)
			(end -0.67945 -0.305054)
			(stroke
				(width 0.1)
				(type default)
			)
			(layer "F.Fab")
		)
		(fp_line
			(start -0.12065 0.3048)
			(end -0.67945 0.3048)
			(stroke
				(width 0.1)
				(type default)
			)
			(layer "F.Fab")
		)
		(fp_line
			(start 0.120396 0.3048)
			(end 0.120396 0.2794)
			(stroke
				(width 0.1)
				(type default)
			)
			(layer "F.Fab")
		)
		(fp_line
			(start 0.67945 0.3048)
			(end 0.120396 0.3048)
			(stroke
				(width 0.1)
				(type default)
			)
			(layer "F.Fab")
		)
		(fp_line
			(start -0.12065 0.2794)
			(end -0.12065 0.3048)
			(stroke
				(width 0.1)
				(type default)
			)
			(layer "F.Fab")
		)
		(fp_line
			(start 0.120396 0.2794)
			(end -0.12065 0.2794)
			(stroke
				(width 0.1)
				(type default)
			)
			(layer "F.Fab")
		)
		(fp_line
			(start -0.12065 -0.2794)
			(end 0.12065 -0.2794)
			(stroke
				(width 0.1)
				(type default)
			)
			(layer "F.Fab")
		)
		(fp_line
			(start 0.12065 -0.2794)
			(end 0.12065 -0.3048)
			(stroke
				(width 0.1)
				(type default)
			)
			(layer "F.Fab")
		)
		(fp_line
			(start 0.12065 -0.3048)
			(end 0.67945 -0.3048)
			(stroke
				(width 0.1)
				(type default)
			)
			(layer "F.Fab")
		)
		(fp_line
			(start 0.67945 -0.3048)
			(end 0.67945 0.3048)
			(stroke
				(width 0.1)
				(type default)
			)
			(layer "F.Fab")
		)
		(fp_line
			(start -0.67945 -0.305054)
			(end -0.12065 -0.305054)
			(stroke
				(width 0.1)
				(type default)
			)
			(layer "F.Fab")
		)
		(fp_line
			(start -0.12065 -0.305054)
			(end -0.12065 -0.2794)
			(stroke
				(width 0.1)
				(type default)
			)
			(layer "F.Fab")
		)
		(pad "1" smd circle
			(at -0.40005 0 270)
			(size 0 0)
			(layers "F.Cu" "F.Mask" "F.Paste")
			(net "PEX2_MODE_SEL7")
		)
		(pad "2" smd circle
			(at 0.40005 0 270)
			(size 0 0)
			(layers "F.Cu" "F.Mask" "F.Paste")
			(net "P1V8_PEX")
		)
	)
	(footprint ""
		(layer "F.Cu")
		(at 17.792446 -31.825184 180)
		(property "Reference" "C68"
			(at 0 0 180)
			(layer "F.SilkS")
			(hide yes)
			(effects
				(font
					(size 1.27 1.27)
				)
			)
		)
		(property "Value" ""
			(at 0 0 180)
			(layer "F.Fab")
			(effects
				(font
					(size 1.27 1.27)
				)
			)
		)
		(duplicate_pad_numbers_are_jumpers no)
		(fp_line
			(start 0.299974 0.150114)
			(end -0.299974 0.150114)
			(stroke
				(width 0.1)
				(type default)
			)
			(layer "F.Fab")
		)
		(fp_line
			(start 0.299974 -0.150114)
			(end 0.299974 0.150114)
			(stroke
				(width 0.1)
				(type default)
			)
			(layer "F.Fab")
		)
		(fp_line
			(start -0.299974 0.150114)
			(end -0.299974 -0.150114)
			(stroke
				(width 0.1)
				(type default)
			)
			(layer "F.Fab")
		)
		(fp_line
			(start -0.299974 -0.150114)
			(end 0.299974 -0.150114)
			(stroke
				(width 0.1)
				(type default)
			)
			(layer "F.Fab")
		)
		(pad "1" smd rect
			(at -0.2667 0 180)
			(size 0.3048 0.381)
			(layers "F.Cu" "F.Mask" "F.Paste")
			(net "P5E_PEX0_STN2_TX_DN<46>")
		)
		(pad "2" smd rect
			(at 0.2667 0 180)
			(size 0.3048 0.381)
			(layers "F.Cu" "F.Mask" "F.Paste")
			(net "P5E_PEX0_STN2_TX_C_DN<46>")
		)
	)
	(footprint ""
		(layer "F.Cu")
		(at 148.511514 -290.044632 -90)
		(property "Reference" "R4572"
			(at 0 0 270)
			(layer "F.SilkS")
			(hide yes)
			(effects
				(font
					(size 1.27 1.27)
				)
			)
		)
		(property "Value" ""
			(at 0 0 270)
			(layer "F.Fab")
			(effects
				(font
					(size 1.27 1.27)
				)
			)
		)
		(duplicate_pad_numbers_are_jumpers no)
		(fp_line
			(start -0.7874 0.4064)
			(end -0.7874 -0.4064)
			(stroke
				(width 0.1524)
				(type default)
			)
			(layer "F.SilkS")
		)
		(fp_line
			(start 0.7874 0.4064)
			(end -0.7874 0.4064)
			(stroke
				(width 0.1524)
				(type default)
			)
			(layer "F.SilkS")
		)
		(fp_line
			(start -0.7874 -0.4064)
			(end 0.7874 -0.4064)
			(stroke
				(width 0.1524)
				(type default)
			)
			(layer "F.SilkS")
		)
		(fp_line
			(start 0.7874 -0.4064)
			(end 0.7874 0.4064)
			(stroke
				(width 0.1524)
				(type default)
			)
			(layer "F.SilkS")
		)
		(fp_line
			(start -0.67945 0.3048)
			(end -0.67945 -0.305054)
			(stroke
				(width 0.1)
				(type default)
			)
			(layer "F.Fab")
		)
		(fp_line
			(start -0.12065 0.3048)
			(end -0.67945 0.3048)
			(stroke
				(width 0.1)
				(type default)
			)
			(layer "F.Fab")
		)
		(fp_line
			(start 0.120396 0.3048)
			(end 0.120396 0.2794)
			(stroke
				(width 0.1)
				(type default)
			)
			(layer "F.Fab")
		)
		(fp_line
			(start 0.67945 0.3048)
			(end 0.120396 0.3048)
			(stroke
				(width 0.1)
				(type default)
			)
			(layer "F.Fab")
		)
		(fp_line
			(start -0.12065 0.2794)
			(end -0.12065 0.3048)
			(stroke
				(width 0.1)
				(type default)
			)
			(layer "F.Fab")
		)
		(fp_line
			(start 0.120396 0.2794)
			(end -0.12065 0.2794)
			(stroke
				(width 0.1)
				(type default)
			)
			(layer "F.Fab")
		)
		(fp_line
			(start -0.12065 -0.2794)
			(end 0.12065 -0.2794)
			(stroke
				(width 0.1)
				(type default)
			)
			(layer "F.Fab")
		)
		(fp_line
			(start 0.12065 -0.2794)
			(end 0.12065 -0.3048)
			(stroke
				(width 0.1)
				(type default)
			)
			(layer "F.Fab")
		)
		(fp_line
			(start 0.12065 -0.3048)
			(end 0.67945 -0.3048)
			(stroke
				(width 0.1)
				(type default)
			)
			(layer "F.Fab")
		)
		(fp_line
			(start 0.67945 -0.3048)
			(end 0.67945 0.3048)
			(stroke
				(width 0.1)
				(type default)
			)
			(layer "F.Fab")
		)
		(fp_line
			(start -0.67945 -0.305054)
			(end -0.12065 -0.305054)
			(stroke
				(width 0.1)
				(type default)
			)
			(layer "F.Fab")
		)
		(fp_line
			(start -0.12065 -0.305054)
			(end -0.12065 -0.2794)
			(stroke
				(width 0.1)
				(type default)
			)
			(layer "F.Fab")
		)
		(pad "1" smd circle
			(at -0.40005 0 270)
			(size 0 0)
			(layers "F.Cu" "F.Mask" "F.Paste")
			(net "PCEPLL4_VDDA18_PEX1")
		)
		(pad "2" smd circle
			(at 0.40005 0 270)
			(size 0 0)
			(layers "F.Cu" "F.Mask" "F.Paste")
			(net "PCEPLL4_VDDA18_PEX1_R")
		)
	)
	(footprint ""
		(layer "F.Cu")
		(at 336.042 -141.859)
		(property "Reference" "R4796"
			(at 0 0 0)
			(layer "F.SilkS")
			(hide yes)
			(effects
				(font
					(size 1.27 1.27)
				)
			)
		)
		(property "Value" ""
			(at 0 0 0)
			(layer "F.Fab")
			(effects
				(font
					(size 1.27 1.27)
				)
			)
		)
		(duplicate_pad_numbers_are_jumpers no)
		(fp_line
			(start -0.7874 -0.4064)
			(end 0.7874 -0.4064)
			(stroke
				(width 0.1524)
				(type default)
			)
			(layer "F.SilkS")
		)
		(fp_line
			(start -0.7874 0.4064)
			(end -0.7874 -0.4064)
			(stroke
				(width 0.1524)
				(type default)
			)
			(layer "F.SilkS")
		)
		(fp_line
			(start 0.7874 -0.4064)
			(end 0.7874 0.4064)
			(stroke
				(width 0.1524)
				(type default)
			)
			(layer "F.SilkS")
		)
		(fp_line
			(start 0.7874 0.4064)
			(end -0.7874 0.4064)
			(stroke
				(width 0.1524)
				(type default)
			)
			(layer "F.SilkS")
		)
		(fp_line
			(start -0.67945 -0.305054)
			(end -0.12065 -0.305054)
			(stroke
				(width 0.1)
				(type default)
			)
			(layer "F.Fab")
		)
		(fp_line
			(start -0.67945 0.3048)
			(end -0.67945 -0.305054)
			(stroke
				(width 0.1)
				(type default)
			)
			(layer "F.Fab")
		)
		(fp_line
			(start -0.12065 -0.305054)
			(end -0.12065 -0.2794)
			(stroke
				(width 0.1)
				(type default)
			)
			(layer "F.Fab")
		)
		(fp_line
			(start -0.12065 -0.2794)
			(end 0.12065 -0.2794)
			(stroke
				(width 0.1)
				(type default)
			)
			(layer "F.Fab")
		)
		(fp_line
			(start -0.12065 0.2794)
			(end -0.12065 0.3048)
			(stroke
				(width 0.1)
				(type default)
			)
			(layer "F.Fab")
		)
		(fp_line
			(start -0.12065 0.3048)
			(end -0.67945 0.3048)
			(stroke
				(width 0.1)
				(type default)
			)
			(layer "F.Fab")
		)
		(fp_line
			(start 0.120396 0.2794)
			(end -0.12065 0.2794)
			(stroke
				(width 0.1)
				(type default)
			)
			(layer "F.Fab")
		)
		(fp_line
			(start 0.120396 0.3048)
			(end 0.120396 0.2794)
			(stroke
				(width 0.1)
				(type default)
			)
			(layer "F.Fab")
		)
		(fp_line
			(start 0.12065 -0.3048)
			(end 0.67945 -0.3048)
			(stroke
				(width 0.1)
				(type default)
			)
			(layer "F.Fab")
		)
		(fp_line
			(start 0.12065 -0.2794)
			(end 0.12065 -0.3048)
			(stroke
				(width 0.1)
				(type default)
			)
			(layer "F.Fab")
		)
		(fp_line
			(start 0.67945 -0.3048)
			(end 0.67945 0.3048)
			(stroke
				(width 0.1)
				(type default)
			)
			(layer "F.Fab")
		)
		(fp_line
			(start 0.67945 0.3048)
			(end 0.120396 0.3048)
			(stroke
				(width 0.1)
				(type default)
			)
			(layer "F.Fab")
		)
		(pad "1" smd circle
			(at -0.40005 0)
			(size 0 0)
			(layers "F.Cu" "F.Mask" "F.Paste")
			(net "P3V3_AUX")
		)
		(pad "2" smd circle
			(at 0.40005 0)
			(size 0 0)
			(layers "F.Cu" "F.Mask" "F.Paste")
			(net "RST_PEX_SSD15_PERST_R_N")
		)
	)
	(footprint ""
		(layer "F.Cu")
		(at 136.275064 -48.753014 180)
		(property "Reference" "C315"
			(at 0 0 180)
			(layer "F.SilkS")
			(hide yes)
			(effects
				(font
					(size 1.27 1.27)
				)
			)
		)
		(property "Value" ""
			(at 0 0 180)
			(layer "F.Fab")
			(effects
				(font
					(size 1.27 1.27)
				)
			)
		)
		(duplicate_pad_numbers_are_jumpers no)
		(fp_line
			(start 0.7874 0.4064)
			(end -0.7874 0.4064)
			(stroke
				(width 0.1524)
				(type default)
			)
			(layer "F.SilkS")
		)
		(fp_line
			(start 0.7874 -0.4064)
			(end 0.7874 0.4064)
			(stroke
				(width 0.1524)
				(type default)
			)
			(layer "F.SilkS")
		)
		(fp_line
			(start -0.7874 0.4064)
			(end -0.7874 -0.4064)
			(stroke
				(width 0.1524)
				(type default)
			)
			(layer "F.SilkS")
		)
		(fp_line
			(start -0.7874 -0.4064)
			(end 0.7874 -0.4064)
			(stroke
				(width 0.1524)
				(type default)
			)
			(layer "F.SilkS")
		)
		(fp_line
			(start 0.67945 0.3048)
			(end 0.120396 0.3048)
			(stroke
				(width 0.1)
				(type default)
			)
			(layer "F.Fab")
		)
		(fp_line
			(start 0.67945 -0.3048)
			(end 0.67945 0.3048)
			(stroke
				(width 0.1)
				(type default)
			)
			(layer "F.Fab")
		)
		(fp_line
			(start 0.12065 -0.2794)
			(end 0.12065 -0.3048)
			(stroke
				(width 0.1)
				(type default)
			)
			(layer "F.Fab")
		)
		(fp_line
			(start 0.12065 -0.3048)
			(end 0.67945 -0.3048)
			(stroke
				(width 0.1)
				(type default)
			)
			(layer "F.Fab")
		)
		(fp_line
			(start 0.120396 0.3048)
			(end 0.120396 0.2794)
			(stroke
				(width 0.1)
				(type default)
			)
			(layer "F.Fab")
		)
		(fp_line
			(start 0.120396 0.2794)
			(end -0.12065 0.2794)
			(stroke
				(width 0.1)
				(type default)
			)
			(layer "F.Fab")
		)
		(fp_line
			(start -0.12065 0.3048)
			(end -0.67945 0.3048)
			(stroke
				(width 0.1)
				(type default)
			)
			(layer "F.Fab")
		)
		(fp_line
			(start -0.12065 0.2794)
			(end -0.12065 0.3048)
			(stroke
				(width 0.1)
				(type default)
			)
			(layer "F.Fab")
		)
		(fp_line
			(start -0.12065 -0.2794)
			(end 0.12065 -0.2794)
			(stroke
				(width 0.1)
				(type default)
			)
			(layer "F.Fab")
		)
		(fp_line
			(start -0.12065 -0.305054)
			(end -0.12065 -0.2794)
			(stroke
				(width 0.1)
				(type default)
			)
			(layer "F.Fab")
		)
		(fp_line
			(start -0.67945 0.3048)
			(end -0.67945 -0.305054)
			(stroke
				(width 0.1)
				(type default)
			)
			(layer "F.Fab")
		)
		(fp_line
			(start -0.67945 -0.305054)
			(end -0.12065 -0.305054)
			(stroke
				(width 0.1)
				(type default)
			)
			(layer "F.Fab")
		)
		(pad "1" smd circle
			(at -0.40005 0 180)
			(size 0 0)
			(layers "F.Cu" "F.Mask" "F.Paste")
			(net "P3V3_AUX")
		)
		(pad "2" smd circle
			(at 0.40005 0 180)
			(size 0 0)
			(layers "F.Cu" "F.Mask" "F.Paste")
			(net "GND")
		)
	)
)
